(kicad_pcb
	(version 20260206)
	(generator "pcbnew")
	(generator_version "10.0")
	(general
		(thickness 1.6)
		(legacy_teardrops no)
	)
	(paper "A4")
	(title_block
		(title "baseboard — 13948-1b.1110WZS1818.brd")
		(comment 1 "Honey Badger (Wiwynn) / footprints 737-743 of 2523")
	)
	(layers
		(0 "F.Cu" signal "TOP")
		(4 "In1.Cu" signal "L2GND")
		(6 "In2.Cu" signal "L3")
		(8 "In3.Cu" signal "L4VCC")
		(10 "In4.Cu" signal "L5VCC")
		(12 "In5.Cu" signal "L6")
		(14 "In6.Cu" signal "L7GND")
		(2 "B.Cu" signal "BOTTOM")
		(9 "F.Adhes" user "F.Adhesive")
		(11 "B.Adhes" user "B.Adhesive")
		(13 "F.Paste" user "Package Geometry/Pastemask Top")
		(15 "B.Paste" user "Package Geometry/Pastemask Bottom")
		(5 "F.SilkS" user "Ref Des/Silkscreen Top")
		(7 "B.SilkS" user "Ref Des/Silkscreen Bottom")
		(1 "F.Mask" user "Board Geometry/Soldermask Top")
		(3 "B.Mask" user "Board Geometry/Soldermask Bottom")
		(17 "Dwgs.User" user "User.Drawings")
		(19 "Cmts.User" user "User.Comments")
		(21 "Eco1.User" user "User.Eco1")
		(23 "Eco2.User" user "User.Eco2")
		(25 "Edge.Cuts" user "Board Geometry/Outline")
		(27 "Margin" user)
		(31 "F.CrtYd" user "Package Geometry/Place Bound Top")
		(29 "B.CrtYd" user "Package Geometry/Place Bound Bottom")
		(35 "F.Fab" user "Ref Des/Assembly Top")
		(33 "B.Fab" user "Ref Des/Assembly Bottom")
	)
	(footprint ""
		(layer "F.Cu")
		(at 194.818 -120.269)
		(property "Reference" "R599"
			(at 0 0 0)
			(layer "F.SilkS")
			(hide yes)
			(effects
				(font
					(size 1.27 1.27)
				)
			)
		)
		(property "Value" "4K7R2F-GP"
			(at 0.064008 -3.993896 0)
			(unlocked yes)
			(layer "F.Fab")
			(hide yes)
			(effects
				(font
					(size 1.016 1.016)
					(thickness 0.1524)
				)
			)
		)
		(property "Device Type" "R402H16"
			(at 0.064008 -5.517896 0)
			(unlocked yes)
			(layer "F.Fab")
			(hide yes)
			(effects
				(font
					(size 1.016 1.016)
					(thickness 0.1524)
				)
			)
		)
		(duplicate_pad_numbers_are_jumpers no)
		(fp_line
			(start -0.508 -0.9398)
			(end -0.508 0.9398)
			(stroke
				(width 0.1524)
				(type default)
			)
			(layer "F.SilkS")
		)
		(fp_line
			(start 0.508 -0.9398)
			(end -0.508 -0.9398)
			(stroke
				(width 0.1524)
				(type default)
			)
			(layer "F.SilkS")
		)
		(fp_rect
			(start -0.508 0.9398)
			(end 0.508 -0.9398)
			(stroke
				(width 0)
				(type default)
			)
			(fill no)
			(layer "F.CrtYd")
		)
		(fp_rect
			(start -0.508 0.9398)
			(end 0.508 -0.9398)
			(stroke
				(width 0)
				(type default)
			)
			(fill no)
			(layer "F.Fab")
		)
		(pad "1" smd custom
			(at 0 -0.4445)
			(size 0.1397 0.1397)
			(layers "F.Cu" "F.Mask" "F.Paste")
			(net "P3V3_STBY")
			(options
				(clearance outline)
				(anchor circle)
			)
			(primitives
				(gr_poly
					(pts
						(arc
							(start -0.1778 -0.2794)
							(mid -0.249642 -0.249642)
							(end -0.2794 -0.1778)
						)
						(arc
							(start -0.2794 0.1778)
							(mid -0.249642 0.249642)
							(end -0.1778 0.2794)
						)
						(arc
							(start 0.1778 0.2794)
							(mid 0.249642 0.249642)
							(end 0.2794 0.1778)
						)
						(arc
							(start 0.2794 -0.1778)
							(mid 0.249642 -0.249642)
							(end 0.1778 -0.2794)
						)
					)
					(width 0)
					(fill yes)
				)
			)
		)
		(pad "2" smd custom
			(at 0 0.4445)
			(size 0.1397 0.1397)
			(layers "F.Cu" "F.Mask" "F.Paste")
			(net "P1V8_PG_R_1")
			(options
				(clearance outline)
				(anchor circle)
			)
			(primitives
				(gr_poly
					(pts
						(arc
							(start -0.1778 -0.2794)
							(mid -0.249642 -0.249642)
							(end -0.2794 -0.1778)
						)
						(arc
							(start -0.2794 0.1778)
							(mid -0.249642 0.249642)
							(end -0.1778 0.2794)
						)
						(arc
							(start 0.1778 0.2794)
							(mid 0.249642 0.249642)
							(end 0.2794 0.1778)
						)
						(arc
							(start 0.2794 -0.1778)
							(mid 0.249642 -0.249642)
							(end 0.1778 -0.2794)
						)
					)
					(width 0)
					(fill yes)
				)
			)
		)
	)
	(footprint ""
		(layer "F.Cu")
		(at 36.449 -175.82134)
		(property "Reference" "SQ16"
			(at 0 0 0)
			(layer "F.SilkS")
			(hide yes)
			(effects
				(font
					(size 1.27 1.27)
				)
			)
		)
		(property "Value" "2N7002A-7-GP"
			(at 0.127 -8.9662 0)
			(unlocked yes)
			(layer "F.Fab")
			(hide yes)
			(effects
				(font
					(size 1.016 1.016)
					(thickness 0.1524)
				)
			)
		)
		(property "Device Type" "SOT23DGS2D4H48"
			(at 0.127 -10.4902 0)
			(unlocked yes)
			(layer "F.Fab")
			(hide yes)
			(effects
				(font
					(size 1.016 1.016)
					(thickness 0.1524)
				)
			)
		)
		(duplicate_pad_numbers_are_jumpers no)
		(fp_line
			(start -1.651 -1.778)
			(end -1.651 1.778)
			(stroke
				(width 0.1524)
				(type default)
			)
			(layer "F.SilkS")
		)
		(fp_line
			(start -1.651 1.778)
			(end 1.651 1.778)
			(stroke
				(width 0.1524)
				(type default)
			)
			(layer "F.SilkS")
		)
		(fp_line
			(start 1.651 -1.778)
			(end -1.651 -1.778)
			(stroke
				(width 0.1524)
				(type default)
			)
			(layer "F.SilkS")
		)
		(fp_line
			(start 1.651 1.778)
			(end 1.651 -1.778)
			(stroke
				(width 0.1524)
				(type default)
			)
			(layer "F.SilkS")
		)
		(fp_poly
			(pts
				(xy -1.778 1.8796) (xy -1.778 -1.8796) (xy 1.778 -1.8796) (xy 1.778 1.8796)
			)
			(stroke
				(width 0)
				(type default)
			)
			(fill no)
			(layer "F.CrtYd")
		)
		(fp_poly
			(pts
				(xy -1.778 1.8796) (xy -1.778 -1.8796) (xy 1.778 -1.8796) (xy 1.778 1.8796)
			)
			(stroke
				(width 0)
				(type default)
			)
			(fill no)
			(layer "F.Fab")
		)
		(pad "D" smd custom
			(at 0 -0.9525)
			(size 0.1905 0.1905)
			(layers "F.Cu" "F.Mask" "F.Paste")
			(net "DP_EXP_RST_R")
			(options
				(clearance outline)
				(anchor circle)
			)
			(primitives
				(gr_poly
					(pts
						(arc
							(start -0.1778 0.5715)
							(mid -0.321484 0.511984)
							(end -0.381 0.3683)
						)
						(arc
							(start -0.381 -0.3683)
							(mid -0.321484 -0.511984)
							(end -0.1778 -0.5715)
						)
						(arc
							(start 0.1778 -0.5715)
							(mid 0.321484 -0.511984)
							(end 0.381 -0.3683)
						)
						(arc
							(start 0.381 0.3683)
							(mid 0.321484 0.511984)
							(end 0.1778 0.5715)
						)
					)
					(width 0)
					(fill yes)
				)
			)
		)
		(pad "G" smd custom
			(at -0.98425 0.9525)
			(size 0.1905 0.1905)
			(layers "F.Cu" "F.Mask" "F.Paste")
			(net "P3V3_STBY_G8")
			(options
				(clearance outline)
				(anchor circle)
			)
			(primitives
				(gr_poly
					(pts
						(arc
							(start -0.1778 0.5715)
							(mid -0.321484 0.511984)
							(end -0.381 0.3683)
						)
						(arc
							(start -0.381 -0.3683)
							(mid -0.321484 -0.511984)
							(end -0.1778 -0.5715)
						)
						(arc
							(start 0.1778 -0.5715)
							(mid 0.321484 -0.511984)
							(end 0.381 -0.3683)
						)
						(arc
							(start 0.381 0.3683)
							(mid 0.321484 0.511984)
							(end 0.1778 0.5715)
						)
					)
					(width 0)
					(fill yes)
				)
			)
		)
		(pad "S" smd custom
			(at 0.98425 0.9525)
			(size 0.1905 0.1905)
			(layers "F.Cu" "F.Mask" "F.Paste")
			(net "GND")
			(options
				(clearance outline)
				(anchor circle)
			)
			(primitives
				(gr_poly
					(pts
						(arc
							(start -0.1778 0.5715)
							(mid -0.321484 0.511984)
							(end -0.381 0.3683)
						)
						(arc
							(start -0.381 -0.3683)
							(mid -0.321484 -0.511984)
							(end -0.1778 -0.5715)
						)
						(arc
							(start 0.1778 -0.5715)
							(mid 0.321484 -0.511984)
							(end 0.381 -0.3683)
						)
						(arc
							(start 0.381 0.3683)
							(mid 0.321484 0.511984)
							(end 0.1778 0.5715)
						)
					)
					(width 0)
					(fill yes)
				)
			)
		)
	)
	(footprint ""
		(layer "F.Cu")
		(at 9.856216 -228.65588 180)
		(property "Reference" "R519"
			(at 0 0 180)
			(layer "F.SilkS")
			(hide yes)
			(effects
				(font
					(size 1.27 1.27)
				)
			)
		)
		(property "Value" "10KR2F-2-GP"
			(at 0.064008 -3.993896 180)
			(unlocked yes)
			(layer "F.Fab")
			(hide yes)
			(effects
				(font
					(size 1.016 1.016)
					(thickness 0.1524)
				)
			)
		)
		(property "Device Type" "R402H16"
			(at 0.064008 -5.517896 180)
			(unlocked yes)
			(layer "F.Fab")
			(hide yes)
			(effects
				(font
					(size 1.016 1.016)
					(thickness 0.1524)
				)
			)
		)
		(duplicate_pad_numbers_are_jumpers no)
		(fp_line
			(start 0.508 -0.9398)
			(end -0.508 -0.9398)
			(stroke
				(width 0.1524)
				(type default)
			)
			(layer "F.SilkS")
		)
		(fp_line
			(start -0.508 -0.9398)
			(end -0.508 0.9398)
			(stroke
				(width 0.1524)
				(type default)
			)
			(layer "F.SilkS")
		)
		(fp_rect
			(start -0.508 0.9398)
			(end 0.508 -0.9398)
			(stroke
				(width 0)
				(type default)
			)
			(fill no)
			(layer "F.CrtYd")
		)
		(fp_rect
			(start -0.508 0.9398)
			(end 0.508 -0.9398)
			(stroke
				(width 0)
				(type default)
			)
			(fill no)
			(layer "F.Fab")
		)
		(pad "1" smd custom
			(at 0 -0.4445 180)
			(size 0.1397 0.1397)
			(layers "F.Cu" "F.Mask" "F.Paste")
			(net "PCIE_MATED#_A")
			(options
				(clearance outline)
				(anchor circle)
			)
			(primitives
				(gr_poly
					(pts
						(arc
							(start -0.1778 -0.2794)
							(mid -0.249642 -0.249642)
							(end -0.2794 -0.1778)
						)
						(arc
							(start -0.2794 0.1778)
							(mid -0.249642 0.249642)
							(end -0.1778 0.2794)
						)
						(arc
							(start 0.1778 0.2794)
							(mid 0.249642 0.249642)
							(end 0.2794 0.1778)
						)
						(arc
							(start 0.2794 -0.1778)
							(mid 0.249642 -0.249642)
							(end 0.1778 -0.2794)
						)
					)
					(width 0)
					(fill yes)
				)
			)
		)
		(pad "2" smd custom
			(at 0 0.4445 180)
			(size 0.1397 0.1397)
			(layers "F.Cu" "F.Mask" "F.Paste")
			(net "GND")
			(options
				(clearance outline)
				(anchor circle)
			)
			(primitives
				(gr_poly
					(pts
						(arc
							(start -0.1778 -0.2794)
							(mid -0.249642 -0.249642)
							(end -0.2794 -0.1778)
						)
						(arc
							(start -0.2794 0.1778)
							(mid -0.249642 0.249642)
							(end -0.1778 0.2794)
						)
						(arc
							(start 0.1778 0.2794)
							(mid 0.249642 0.249642)
							(end 0.2794 0.1778)
						)
						(arc
							(start 0.2794 -0.1778)
							(mid 0.249642 -0.249642)
							(end 0.1778 -0.2794)
						)
					)
					(width 0)
					(fill yes)
				)
			)
		)
	)
	(footprint ""
		(layer "F.Cu")
		(at 86.49716 -36.322 -90)
		(property "Reference" "SC882"
			(at 0 0 270)
			(layer "F.SilkS")
			(hide yes)
			(effects
				(font
					(size 1.27 1.27)
				)
			)
		)
		(property "Value" "SCD01U10V1KX-GP"
			(at -2.8321 -1.7399 270)
			(unlocked yes)
			(layer "F.Fab")
			(hide yes)
			(effects
				(font
					(size 1.016 1.016)
					(thickness 0.1524)
				)
			)
		)
		(property "Device Type" "C0201H13"
			(at -2.8321 -3.2639 270)
			(unlocked yes)
			(layer "F.Fab")
			(hide yes)
			(effects
				(font
					(size 1.016 1.016)
					(thickness 0.1524)
				)
			)
		)
		(duplicate_pad_numbers_are_jumpers no)
		(fp_rect
			(start -0.2794 0.6477)
			(end 0.2794 -0.6477)
			(stroke
				(width 0)
				(type default)
			)
			(fill no)
			(layer "F.CrtYd")
		)
		(fp_rect
			(start -0.2794 0.6477)
			(end 0.2794 -0.6477)
			(stroke
				(width 0)
				(type default)
			)
			(fill no)
			(layer "F.Fab")
		)
		(pad "1" smd custom
			(at 0 -0.2794 270)
			(size 0.0762 0.0762)
			(layers "F.Cu" "F.Mask" "F.Paste")
			(net "SAS3008_RAID_TX_C_N2")
			(options
				(clearance outline)
				(anchor circle)
			)
			(primitives
				(gr_poly
					(pts
						(arc
							(start 0.1524 -0.127)
							(mid 0.137521 -0.162921)
							(end 0.1016 -0.1778)
						)
						(arc
							(start -0.1016 -0.1778)
							(mid -0.137521 -0.162921)
							(end -0.1524 -0.127)
						)
						(arc
							(start -0.1524 0.127)
							(mid -0.137521 0.162921)
							(end -0.1016 0.1778)
						)
						(arc
							(start 0.1016 0.1778)
							(mid 0.137521 0.162921)
							(end 0.1524 0.127)
						)
					)
					(width 0)
					(fill yes)
				)
			)
		)
		(pad "2" smd custom
			(at 0 0.2794 270)
			(size 0.0762 0.0762)
			(layers "F.Cu" "F.Mask" "F.Paste")
			(net "SAS3008_RAID_TX_N2")
			(options
				(clearance outline)
				(anchor circle)
			)
			(primitives
				(gr_poly
					(pts
						(arc
							(start 0.1524 -0.127)
							(mid 0.137521 -0.162921)
							(end 0.1016 -0.1778)
						)
						(arc
							(start -0.1016 -0.1778)
							(mid -0.137521 -0.162921)
							(end -0.1524 -0.127)
						)
						(arc
							(start -0.1524 0.127)
							(mid -0.137521 0.162921)
							(end -0.1016 0.1778)
						)
						(arc
							(start 0.1016 0.1778)
							(mid 0.137521 0.162921)
							(end 0.1524 0.127)
						)
					)
					(width 0)
					(fill yes)
				)
			)
		)
	)
	(footprint ""
		(layer "F.Cu")
		(at 197.484492 -175.019716)
		(property "Reference" "Q10"
			(at 0 0 0)
			(layer "F.SilkS")
			(hide yes)
			(effects
				(font
					(size 1.27 1.27)
				)
			)
		)
		(property "Value" "2N7002DW-7F-GP"
			(at -2.3622 -8.2042 0)
			(unlocked yes)
			(layer "F.Fab")
			(hide yes)
			(effects
				(font
					(size 1.016 1.016)
					(thickness 0.1524)
				)
			)
		)
		(property "Device Type" "SOT-363H44"
			(at -2.3622 -10.1092 0)
			(unlocked yes)
			(layer "F.Fab")
			(hide yes)
			(effects
				(font
					(size 1.016 1.016)
					(thickness 0.1524)
				)
			)
		)
		(duplicate_pad_numbers_are_jumpers no)
		(fp_line
			(start -1.4478 -1.7018)
			(end -1.4478 1.7018)
			(stroke
				(width 0.1524)
				(type default)
			)
			(layer "F.SilkS")
		)
		(fp_line
			(start -1.4478 1.7018)
			(end 1.4478 1.7018)
			(stroke
				(width 0.1524)
				(type default)
			)
			(layer "F.SilkS")
		)
		(fp_line
			(start -1.27 1.524)
			(end -1.27 0.6604)
			(stroke
				(width 0.4826)
				(type default)
			)
			(layer "F.SilkS")
		)
		(fp_line
			(start 1.4478 -1.7018)
			(end -1.4478 -1.7018)
			(stroke
				(width 0.1524)
				(type default)
			)
			(layer "F.SilkS")
		)
		(fp_line
			(start 1.4478 1.7018)
			(end 1.4478 -1.7018)
			(stroke
				(width 0.1524)
				(type default)
			)
			(layer "F.SilkS")
		)
		(fp_poly
			(pts
				(xy -1.524 -1.778) (xy 1.524 -1.778) (xy 1.524 1.778) (xy -1.524 1.778)
			)
			(stroke
				(width 0)
				(type default)
			)
			(fill no)
			(layer "F.CrtYd")
		)
		(fp_poly
			(pts
				(xy -1.524 -1.778) (xy 1.524 -1.778) (xy 1.524 1.778) (xy -1.524 1.778)
			)
			(stroke
				(width 0)
				(type default)
			)
			(fill no)
			(layer "F.Fab")
		)
		(pad "1" smd rect
			(at -0.65024 0.9398)
			(size 0.4064 1.016)
			(layers "F.Cu" "F.Mask" "F.Paste")
			(net "GND")
		)
		(pad "2" smd rect
			(at 0 0.9398)
			(size 0.4064 1.016)
			(layers "F.Cu" "F.Mask" "F.Paste")
			(net "INVERTER_G2")
		)
		(pad "3" smd rect
			(at 0.65024 0.9398)
			(size 0.4064 1.016)
			(layers "F.Cu" "F.Mask" "F.Paste")
			(net "INVERTER_G2")
		)
		(pad "4" smd rect
			(at 0.65024 -0.9398)
			(size 0.4064 1.016)
			(layers "F.Cu" "F.Mask" "F.Paste")
			(net "GND")
		)
		(pad "5" smd rect
			(at 0 -0.9398)
			(size 0.4064 1.016)
			(layers "F.Cu" "F.Mask" "F.Paste")
			(net "INVERTER_G1")
		)
		(pad "6" smd rect
			(at -0.65024 -0.9398)
			(size 0.4064 1.016)
			(layers "F.Cu" "F.Mask" "F.Paste")
			(net "HB_OUT")
		)
	)
	(footprint ""
		(layer "F.Cu")
		(at 103.886 -231.521 90)
		(property "Reference" "R628"
			(at 0 0 90)
			(layer "F.SilkS")
			(hide yes)
			(effects
				(font
					(size 1.27 1.27)
				)
			)
		)
		(property "Value" "0R2J-2-GP"
			(at 0.064008 -3.993896 90)
			(unlocked yes)
			(layer "F.Fab")
			(hide yes)
			(effects
				(font
					(size 1.016 1.016)
					(thickness 0.1524)
				)
			)
		)
		(property "Device Type" "R402H16"
			(at 0.064008 -5.517896 90)
			(unlocked yes)
			(layer "F.Fab")
			(hide yes)
			(effects
				(font
					(size 1.016 1.016)
					(thickness 0.1524)
				)
			)
		)
		(duplicate_pad_numbers_are_jumpers no)
		(fp_line
			(start 0.508 -0.9398)
			(end -0.508 -0.9398)
			(stroke
				(width 0.1524)
				(type default)
			)
			(layer "F.SilkS")
		)
		(fp_line
			(start -0.508 -0.9398)
			(end -0.508 0.9398)
			(stroke
				(width 0.1524)
				(type default)
			)
			(layer "F.SilkS")
		)
		(fp_rect
			(start -0.508 0.9398)
			(end 0.508 -0.9398)
			(stroke
				(width 0)
				(type default)
			)
			(fill no)
			(layer "F.CrtYd")
		)
		(fp_rect
			(start -0.508 0.9398)
			(end 0.508 -0.9398)
			(stroke
				(width 0)
				(type default)
			)
			(fill no)
			(layer "F.Fab")
		)
		(pad "1" smd custom
			(at 0 -0.4445 90)
			(size 0.1397 0.1397)
			(layers "F.Cu" "F.Mask" "F.Paste")
			(net "SAS_FAULT_LED7")
			(options
				(clearance outline)
				(anchor circle)
			)
			(primitives
				(gr_poly
					(pts
						(arc
							(start -0.1778 -0.2794)
							(mid -0.249642 -0.249642)
							(end -0.2794 -0.1778)
						)
						(arc
							(start -0.2794 0.1778)
							(mid -0.249642 0.249642)
							(end -0.1778 0.2794)
						)
						(arc
							(start 0.1778 0.2794)
							(mid 0.249642 0.249642)
							(end 0.2794 0.1778)
						)
						(arc
							(start 0.2794 -0.1778)
							(mid 0.249642 -0.249642)
							(end 0.1778 -0.2794)
						)
					)
					(width 0)
					(fill yes)
				)
			)
		)
		(pad "2" smd custom
			(at 0 0.4445 90)
			(size 0.1397 0.1397)
			(layers "F.Cu" "F.Mask" "F.Paste")
			(net "SAS_HDD_LED_7")
			(options
				(clearance outline)
				(anchor circle)
			)
			(primitives
				(gr_poly
					(pts
						(arc
							(start -0.1778 -0.2794)
							(mid -0.249642 -0.249642)
							(end -0.2794 -0.1778)
						)
						(arc
							(start -0.2794 0.1778)
							(mid -0.249642 0.249642)
							(end -0.1778 0.2794)
						)
						(arc
							(start 0.1778 0.2794)
							(mid 0.249642 0.249642)
							(end 0.2794 0.1778)
						)
						(arc
							(start 0.2794 -0.1778)
							(mid 0.249642 -0.249642)
							(end 0.1778 -0.2794)
						)
					)
					(width 0)
					(fill yes)
				)
			)
		)
	)
	(footprint ""
		(layer "F.Cu")
		(at 288.925 -158.496)
		(property "Reference" "R476"
			(at 0 0 0)
			(layer "F.SilkS")
			(hide yes)
			(effects
				(font
					(size 1.27 1.27)
				)
			)
		)
		(property "Value" "0R2J-2-GP"
			(at 0.064008 -3.993896 0)
			(unlocked yes)
			(layer "F.Fab")
			(hide yes)
			(effects
				(font
					(size 1.016 1.016)
					(thickness 0.1524)
				)
			)
		)
		(property "Device Type" "R402H16"
			(at 0.064008 -5.517896 0)
			(unlocked yes)
			(layer "F.Fab")
			(hide yes)
			(effects
				(font
					(size 1.016 1.016)
					(thickness 0.1524)
				)
			)
		)
		(duplicate_pad_numbers_are_jumpers no)
		(fp_line
			(start -0.508 -0.9398)
			(end -0.508 0.9398)
			(stroke
				(width 0.1524)
				(type default)
			)
			(layer "F.SilkS")
		)
		(fp_line
			(start 0.508 -0.9398)
			(end -0.508 -0.9398)
			(stroke
				(width 0.1524)
				(type default)
			)
			(layer "F.SilkS")
		)
		(fp_rect
			(start -0.508 0.9398)
			(end 0.508 -0.9398)
			(stroke
				(width 0)
				(type default)
			)
			(fill no)
			(layer "F.CrtYd")
		)
		(fp_rect
			(start -0.508 0.9398)
			(end 0.508 -0.9398)
			(stroke
				(width 0)
				(type default)
			)
			(fill no)
			(layer "F.Fab")
		)
		(pad "1" smd custom
			(at 0 -0.4445)
			(size 0.1397 0.1397)
			(layers "F.Cu" "F.Mask" "F.Paste")
			(net "BMC_TXD1")
			(options
				(clearance outline)
				(anchor circle)
			)
			(primitives
				(gr_poly
					(pts
						(arc
							(start -0.1778 -0.2794)
							(mid -0.249642 -0.249642)
							(end -0.2794 -0.1778)
						)
						(arc
							(start -0.2794 0.1778)
							(mid -0.249642 0.249642)
							(end -0.1778 0.2794)
						)
						(arc
							(start 0.1778 0.2794)
							(mid 0.249642 0.249642)
							(end 0.2794 0.1778)
						)
						(arc
							(start 0.2794 -0.1778)
							(mid 0.249642 -0.249642)
							(end 0.1778 -0.2794)
						)
					)
					(width 0)
					(fill yes)
				)
			)
		)
		(pad "2" smd custom
			(at 0 0.4445)
			(size 0.1397 0.1397)
			(layers "F.Cu" "F.Mask" "F.Paste")
			(net "CPU_BMC_UART_TX")
			(options
				(clearance outline)
				(anchor circle)
			)
			(primitives
				(gr_poly
					(pts
						(arc
							(start -0.1778 -0.2794)
							(mid -0.249642 -0.249642)
							(end -0.2794 -0.1778)
						)
						(arc
							(start -0.2794 0.1778)
							(mid -0.249642 0.249642)
							(end -0.1778 0.2794)
						)
						(arc
							(start 0.1778 0.2794)
							(mid 0.249642 0.249642)
							(end 0.2794 0.1778)
						)
						(arc
							(start 0.2794 -0.1778)
							(mid 0.249642 -0.249642)
							(end 0.1778 -0.2794)
						)
					)
					(width 0)
					(fill yes)
				)
			)
		)
	)
)
